# T6G (Grand Teton) — schematic netlist excerpt (pin names and nets, part order shuffled) for the footprints in the layout excerpt that follows; sources: Cadence DE-HDL packaged netlist, KiCad conversion of 04192023_DAF0TMB3IC0_F0TG_MB_C_brd_V02_OCP.brd

R320  Q_RES  10K 1% EMPTY  pkg 0402LF  page 250 : A = P3V3_AUX ; B = PCA9548_PCIE3_ADDR0
R5017  Q_RES  1K 1% EMPTY  pkg 0402LF  page 159 : A = PVDD11_S3_P0 ; B = I3C_SCM_1_R_SDA

(kicad_pcb
	(version 20260206)
	(generator "pcbnew")
	(generator_version "10.0")
	(general
		(thickness 1.6)
		(legacy_teardrops no)
	)
	(paper "A4")
	(title_block
		(title "04192023_DAF0TMB3IC0_F0TG_MB_C_brd_V02_OCP.brd")
		(comment 1 "Grand Teton / footprints 4813-4814 of 8354")
	)
	(layers
		(0 "F.Cu" signal "TOP")
		(4 "In1.Cu" signal "GND")
		(6 "In2.Cu" signal "IN1")
		(8 "In3.Cu" signal "GND1")
		(10 "In4.Cu" signal "IN2")
		(12 "In5.Cu" signal "GND2")
		(14 "In6.Cu" signal "IN3")
		(16 "In7.Cu" signal "GND3")
		(18 "In8.Cu" signal "VCC")
		(20 "In9.Cu" signal "VCC1")
		(22 "In10.Cu" signal "GND4")
		(24 "In11.Cu" signal "IN4")
		(26 "In12.Cu" signal "GND5")
		(28 "In13.Cu" signal "IN5")
		(30 "In14.Cu" signal "GND6")
		(32 "In15.Cu" signal "IN6")
		(34 "In16.Cu" signal "GND7")
		(2 "B.Cu" signal "BOTTOM")
		(9 "F.Adhes" user "F.Adhesive")
		(11 "B.Adhes" user "B.Adhesive")
		(13 "F.Paste" user "Package Geometry/Pastemask Top")
		(15 "B.Paste" user "Package Geometry/Pastemask Bottom")
		(5 "F.SilkS" user "Ref Des/Silkscreen Top")
		(7 "B.SilkS" user "Ref Des/Silkscreen Bottom")
		(1 "F.Mask" user "Board Geometry/Soldermask Top")
		(3 "B.Mask" user "Board Geometry/Soldermask Bottom")
		(17 "Dwgs.User" user "User.Drawings")
		(19 "Cmts.User" user "User.Comments")
		(21 "Eco1.User" user "User.Eco1")
		(23 "Eco2.User" user "User.Eco2")
		(25 "Edge.Cuts" user "Board Geometry/Outline")
		(27 "Margin" user)
		(31 "F.CrtYd" user "Package Geometry/Place Bound Top")
		(29 "B.CrtYd" user "Package Geometry/Place Bound Bottom")
		(35 "F.Fab" user "Ref Des/Assembly Top")
		(33 "B.Fab" user "Ref Des/Assembly Bottom")
	)
	(footprint ""
		(layer "F.Cu")
		(at 442.233558 -169.726864 180)
		(property "Reference" "R5017"
			(at 0 0 180)
			(layer "F.SilkS")
			(hide yes)
			(effects
				(font
					(size 1.27 1.27)
				)
			)
		)
		(property "Value" ""
			(at 0 0 180)
			(layer "F.Fab")
			(effects
				(font
					(size 1.27 1.27)
				)
			)
		)
		(duplicate_pad_numbers_are_jumpers no)
		(fp_line
			(start 0.7874 0.4064)
			(end -0.7874 0.4064)
			(stroke
				(width 0.1524)
				(type default)
			)
			(layer "F.SilkS")
		)
		(fp_line
			(start 0.7874 -0.4064)
			(end 0.7874 0.4064)
			(stroke
				(width 0.1524)
				(type default)
			)
			(layer "F.SilkS")
		)
		(fp_line
			(start -0.7874 0.4064)
			(end -0.7874 -0.4064)
			(stroke
				(width 0.1524)
				(type default)
			)
			(layer "F.SilkS")
		)
		(fp_line
			(start -0.7874 -0.4064)
			(end 0.7874 -0.4064)
			(stroke
				(width 0.1524)
				(type default)
			)
			(layer "F.SilkS")
		)
		(fp_line
			(start 0.67945 0.3048)
			(end 0.120396 0.3048)
			(stroke
				(width 0.1)
				(type default)
			)
			(layer "F.Fab")
		)
		(fp_line
			(start 0.67945 -0.3048)
			(end 0.67945 0.3048)
			(stroke
				(width 0.1)
				(type default)
			)
			(layer "F.Fab")
		)
		(fp_line
			(start 0.12065 -0.2794)
			(end 0.12065 -0.3048)
			(stroke
				(width 0.1)
				(type default)
			)
			(layer "F.Fab")
		)
		(fp_line
			(start 0.12065 -0.3048)
			(end 0.67945 -0.3048)
			(stroke
				(width 0.1)
				(type default)
			)
			(layer "F.Fab")
		)
		(fp_line
			(start 0.120396 0.3048)
			(end 0.120396 0.2794)
			(stroke
				(width 0.1)
				(type default)
			)
			(layer "F.Fab")
		)
		(fp_line
			(start 0.120396 0.2794)
			(end -0.12065 0.2794)
			(stroke
				(width 0.1)
				(type default)
			)
			(layer "F.Fab")
		)
		(fp_line
			(start -0.12065 0.3048)
			(end -0.67945 0.3048)
			(stroke
				(width 0.1)
				(type default)
			)
			(layer "F.Fab")
		)
		(fp_line
			(start -0.12065 0.2794)
			(end -0.12065 0.3048)
			(stroke
				(width 0.1)
				(type default)
			)
			(layer "F.Fab")
		)
		(fp_line
			(start -0.12065 -0.2794)
			(end 0.12065 -0.2794)
			(stroke
				(width 0.1)
				(type default)
			)
			(layer "F.Fab")
		)
		(fp_line
			(start -0.12065 -0.305054)
			(end -0.12065 -0.2794)
			(stroke
				(width 0.1)
				(type default)
			)
			(layer "F.Fab")
		)
		(fp_line
			(start -0.67945 0.3048)
			(end -0.67945 -0.305054)
			(stroke
				(width 0.1)
				(type default)
			)
			(layer "F.Fab")
		)
		(fp_line
			(start -0.67945 -0.305054)
			(end -0.12065 -0.305054)
			(stroke
				(width 0.1)
				(type default)
			)
			(layer "F.Fab")
		)
		(pad "1" smd circle
			(at -0.40005 0 180)
			(size 0 0)
			(layers "F.Cu" "F.Mask" "F.Paste")
			(net "PVDD11_S3_P0")
		)
		(pad "2" smd circle
			(at 0.40005 0 180)
			(size 0 0)
			(layers "F.Cu" "F.Mask" "F.Paste")
			(net "I3C_SCM_1_R_SDA")
		)
	)
	(footprint ""
		(layer "F.Cu")
		(at 277.352252 -125.638814)
		(property "Reference" "R320"
			(at 0 0 0)
			(layer "F.SilkS")
			(hide yes)
			(effects
				(font
					(size 1.27 1.27)
				)
			)
		)
		(property "Value" ""
			(at 0 0 0)
			(layer "F.Fab")
			(effects
				(font
					(size 1.27 1.27)
				)
			)
		)
		(duplicate_pad_numbers_are_jumpers no)
		(fp_line
			(start -0.7874 -0.4064)
			(end 0.7874 -0.4064)
			(stroke
				(width 0.1524)
				(type default)
			)
			(layer "F.SilkS")
		)
		(fp_line
			(start -0.7874 0.4064)
			(end -0.7874 -0.4064)
			(stroke
				(width 0.1524)
				(type default)
			)
			(layer "F.SilkS")
		)
		(fp_line
			(start 0.7874 -0.4064)
			(end 0.7874 0.4064)
			(stroke
				(width 0.1524)
				(type default)
			)
			(layer "F.SilkS")
		)
		(fp_line
			(start 0.7874 0.4064)
			(end -0.7874 0.4064)
			(stroke
				(width 0.1524)
				(type default)
			)
			(layer "F.SilkS")
		)
		(fp_line
			(start -0.67945 -0.305054)
			(end -0.12065 -0.305054)
			(stroke
				(width 0.1)
				(type default)
			)
			(layer "F.Fab")
		)
		(fp_line
			(start -0.67945 0.3048)
			(end -0.67945 -0.305054)
			(stroke
				(width 0.1)
				(type default)
			)
			(layer "F.Fab")
		)
		(fp_line
			(start -0.12065 -0.305054)
			(end -0.12065 -0.2794)
			(stroke
				(width 0.1)
				(type default)
			)
			(layer "F.Fab")
		)
		(fp_line
			(start -0.12065 -0.2794)
			(end 0.12065 -0.2794)
			(stroke
				(width 0.1)
				(type default)
			)
			(layer "F.Fab")
		)
		(fp_line
			(start -0.12065 0.2794)
			(end -0.12065 0.3048)
			(stroke
				(width 0.1)
				(type default)
			)
			(layer "F.Fab")
		)
		(fp_line
			(start -0.12065 0.3048)
			(end -0.67945 0.3048)
			(stroke
				(width 0.1)
				(type default)
			)
			(layer "F.Fab")
		)
		(fp_line
			(start 0.120396 0.2794)
			(end -0.12065 0.2794)
			(stroke
				(width 0.1)
				(type default)
			)
			(layer "F.Fab")
		)
		(fp_line
			(start 0.120396 0.3048)
			(end 0.120396 0.2794)
			(stroke
				(width 0.1)
				(type default)
			)
			(layer "F.Fab")
		)
		(fp_line
			(start 0.12065 -0.3048)
			(end 0.67945 -0.3048)
			(stroke
				(width 0.1)
				(type default)
			)
			(layer "F.Fab")
		)
		(fp_line
			(start 0.12065 -0.2794)
			(end 0.12065 -0.3048)
			(stroke
				(width 0.1)
				(type default)
			)
			(layer "F.Fab")
		)
		(fp_line
			(start 0.67945 -0.3048)
			(end 0.67945 0.3048)
			(stroke
				(width 0.1)
				(type default)
			)
			(layer "F.Fab")
		)
		(fp_line
			(start 0.67945 0.3048)
			(end 0.120396 0.3048)
			(stroke
				(width 0.1)
				(type default)
			)
			(layer "F.Fab")
		)
		(pad "1" smd circle
			(at -0.40005 0)
			(size 0 0)
			(layers "F.Cu" "F.Mask" "F.Paste")
			(net "P3V3_AUX")
		)
		(pad "2" smd circle
			(at 0.40005 0)
			(size 0 0)
			(layers "F.Cu" "F.Mask" "F.Paste")
			(net "PCA9548_PCIE3_ADDR0")
		)
	)
)
